FILE_TYPE = CONNECTIVITY;
{Allegro Design Entry HDL 16.6-p007 (v16-6-112F) 10/10/2012}
"PAGE_NUMBER" = 204;
0"NC";
1"GND\g";
2"PVCCIN_CPU0\g";
3"VR_FET_SW_P12V_STBY_PVCCIN_CPU0\g";
4"GND\g";
5"VR_FET_SW_P12V_STBY_PVCCIN_CPU0\g";
6"GND\g";
7"PVCCIN_CPU0\g";
8"GND\g";
9"P12V_STBY\g";
10"P5V_STBY\g";
11"GND\g";
12"GND\g";
13"GND\g";
14"GND\g";
15"GND\g";
16"VSENSE_PVCCIN_CPU0_P";
17"VR_PVCCIN_CPU0_PH5_PHASE"VOLTAGE"5";
18"VR_PVCCIN_CPU0_AIREF5";
19"VR_PVCCIN_CPU0_PH5_VCIN"VOLTAGE"5";
20"TP_PVCCIN_CPU0_PH5_GL_0";
21"VR_PVCCIN_CPU0_PWM5";
22"VR_PVCCIN_CPU0_PHASE5"VOLTAGE"5";
23"VR_PVCCIN_CPU0_PH5_BOOT_R";
24"VR_PVCCIN_CPU0_PHASE5_RC";
25"VR_PVCCIN_CPU0_PH5_BOOT";
26"TP_PVCCIN_CPU0_PH5_GL_1";
27"A_TSENSE_PVCCIN_CPU0";
28"ISENSE_PVCCIN_CPU0_PH5_IMON";
29"VR_PVCCIN_CPU0_PH5_OCSET"VOLTAGE"3.6";
30"VSENSE_PVCCIN_CPU0_N";
31"VSENSE_PVCCIN_CPU0_SKT_VSEN";
32"VSENSE_PVCCIN_CPU0_SKT_VRTN";
%"RES"
"1","(-5550,4750)","0","mstr_discrete","I103";
;
TOLERANCE"5%"
LOCATION"R6P47"
PART_NUMBER"G21497-005"
VALUE"0.0"
PACK_TYPE"0402"
WATTAGE"1/16W"
MATERIAL"CHIP"
CDS_SEC"1"
ROOM"CPU0"
SEC"1"
SEC_TYPE"0402"
CDS_LIB"mstr_discrete"
BOM_COST"PROC_SIDEBAND"
CDS_LOCATION"R6P47";
"B"
$PN"2"10;
"A"
$PN"1"19;
%"IND-120NH-30-GP"
"1","(-1050,3650)","1","w_hdl","I104";
;
CDS_SEC"1"
CDS_LOCATION"L4C3"
TYPE"IRMS=66A@DELTA_T<40C"
RATED"ISAT=94A@25C"
PACK_SIZE"DCR=0.17MOHM"
LOCATION"L4C3"
VALUE"IND-120NH-30-GP"
ATTRIBUTE"120NH"
PACK_TYPE"DISCRET-GB2"
SEC"1"
SEC_TYPE"DISCRET-GB2"
CDS_LMAN_SYM_OUTLINE"-75,100,75,-100"
CDS_LIB"w_hdl"
PART_NUMBER"068.1202N.M001";
"F"
$PN"2"2;
"S"
$PN"1"22;
%"IND-80NH-1-GP"
"1","(-3025,2200)","1","w_hdl","I105";
;
CDS_SEC"1"
CDS_LOCATION"L4C1"
VALUE"IND-80NH-1-GP"
ATTRIBUTE"80NH"
LOCATION"L4C1"
RATED"ISAT=50A@25C"
PACK_SIZE"DCR=0.22MOHM"
TYPE"IRMS=34A@DELTA_T<45C"
PACK_TYPE"DISCRET-GC2"
SEC"1"
SEC_TYPE"DISCRET-GC2"
CDS_LMAN_SYM_OUTLINE"-75,100,75,-100"
CDS_LIB"w_hdl"
PART_NUMBER"068.8001N.M001";
"F"
$PN"2"5;
"S"
$PN"1"9;
%"SC1U10V2KX-4-GP"
"1","(-5200,4150)","0","w_hdl","I113";
;
CDS_SEC"1"
CDS_LOCATION"C4C14"
LOCATION"C4C14"
VALUE"SC1U10V2KX-4-GP"
ATTRIBUTE"1UF"
TOLERANCE"10%"
RATED"10V"
PACK_SIZE"0402"
PACK_TYPE"SMD-BCG6"
SEC"1"
SEC_TYPE"SMD-BCG6"
PART_NUMBER"78.10523.8FL"
CDS_LIB"w_hdl"
CDS_LMAN_SYM_OUTLINE"-50,25,50,-25";
"2"
$PN"2"4;
"1"
$PN"1"10;
%"1R3F-GP"
"1","(-1975,3175)","0","w_hdl","I114";
;
CDS_SEC"1"
CDS_LOCATION"RT24"
POP"NOPOP"
PACK_SIZE"0603"
RATED"1/10W"
LOCATION"RT24"
ATTRIBUTE"1 OHM"
TOLERANCE"1%"
VALUE"1R3F-GP"
PACK_TYPE"RCL_GP"
SEC"1"
SEC_TYPE"RCL_GP"
PART_NUMBER"64.1R005.55L"
CDS_LIB"w_hdl"
CDS_LMAN_SYM_OUTLINE"-50,75,50,-75";
"2"
$PN"2"15;
"1"
$PN"1"24;
%"GND"
"1","(-2475,3275)","0","mstr_symbols","I13";
;
ROOM"PVCCIN_CPU0_PWR_VR"
BOM_COST"PROC_VRD_VCCIN_CPU0"
BODY_TYPE"PLUMBING"
SIZE"1B"
CDS_LIB"mstr_symbols"
VOLTAGE"0"
HDL_POWER"GND";
"A\NAC"1;
%"CAP"
"1","(-4875,4200)","0","mstr_discrete","I18";
;
CDS_SEC"1"
CDS_LOCATION"C4D47"
MATERIAL"X7R"
TOLERANCE"10%"
PART_NUMBER"A36096-155"
PACK_TYPE"0402"
VOLTAGE"16V"
VALUE"0.22UF"
LOCATION"C4D47"
SEC"1"
ROOM"PVCCIN_CPU0_PWR_VR"
SEC_TYPE"0402"
CDS_LIB"mstr_discrete";
"A"
$PN"1"10;
"B"
$PN"2"4;
%"CAP"
"1","(-5825,3575)","2","mstr_discrete","I22";
;
CDS_SEC"1"
LOCATION"C4C17"
TOLERANCE"10%"
VALUE"0.220UF"
VOLTAGE"16V"
MATERIAL"X7R"
PART_NUMBER"A36096-104"
PACK_TYPE"0402"
NO_XNET_CONNECTION"1"
SEC_TYPE"0402"
SPOF"TRUE"
CDS_LIB"mstr_discrete"
SEC"1"
CDS_LOCATION"C4C17"
ROOM"PVCCIN_CPU0_PWR_VR";
"A"
$PN"1"25;
"B"
$PN"2"17;
%"CAP"
"1","(-5700,4175)","0","mstr_discrete","I34";
;
CDS_SEC"1"
CDS_LOCATION"C4D46"
MATERIAL"X6S"
TOLERANCE"10%"
LOCATION"C4D46"
PART_NUMBER"D97712-011"
PACK_TYPE"0402"
VALUE"1.0UF"
VOLTAGE"16V"
CDS_LIB"mstr_discrete"
ROOM"PVCCIN_CPU0_PWR_VR"
SEC"1"
SEC_TYPE"0402";
"A"
$PN"1"19;
"B"
$PN"2"4;
%"CAP_A"
"1","(-6000,4175)","0","dev_discrete","I35";
;
CDS_LOCATION"C4C19"
TOLERANCE"10%"
PACK_TYPE"0402V"
PART_NUMBER"A36096-030"
MATERIAL"X7R"
VALUE"0.1UF"
VOLTAGE"16V"
LOCATION"C4C19"
CDS_LIB"dev_discrete"
SEC"1"
SEC_TYPE"0402V"
CDS_SEC"1"
ROOM"PVCCIN_CPU0_PWR_VR";
"B"
$PN"2"4;
"A"
$PN"1"3;
%"CAP"
"1","(-6300,4175)","0","mstr_discrete","I36";
;
CDS_SEC"1"
CDS_LOCATION"C4C18"
PART_NUMBER"D97712-011"
PACK_TYPE"0402"
MATERIAL"X6S"
LOCATION"C4C18"
VALUE"1.0UF"
VOLTAGE"16V"
TOLERANCE"10%"
SEC_TYPE"0402"
SEC"1"
ROOM"PVCCIN_CPU0_PWR_VR"
CDS_LIB"mstr_discrete";
"A"
$PN"1"3;
"B"
$PN"2"4;
%"CAP"
"1","(-6600,4175)","0","mstr_discrete","I37";
;
CDS_SEC"1"
CDS_LOCATION"C6N10"
PART_NUMBER"C95333-007"
TOLERANCE"10%"
LOCATION"C6N10"
VOLTAGE"16V"
PACK_TYPE"0805"
VALUE"10UF"
MATERIAL"X6S"
SEC_TYPE"0805"
SEC"1"
ROOM"PVCCIN_CPU0_PWR_VR"
CDS_LIB"mstr_discrete";
"A"
$PN"1"3;
"B"
$PN"2"4;
%"CAP"
"1","(-6900,4175)","0","mstr_discrete","I38";
;
CDS_SEC"1"
TOLERANCE"10%"
LOCATION"C6P17"
VALUE"10UF"
VOLTAGE"16V"
PACK_TYPE"0805"
PART_NUMBER"C95333-007"
MATERIAL"X6S"
CDS_LIB"mstr_discrete"
CDS_LOCATION"C6P17"
ROOM"PVCCIN_CPU0_PWR_VR"
SEC_TYPE"0805"
SEC"1";
"A"
$PN"1"3;
"B"
$PN"2"4;
%"PVCCIN_CPU0"
"1","(-400,3725)","0","mstr_symbols","I4";
;
BODY_TYPE"PLUMBING"
VOLTAGE"2.0V"
CDS_LIB"mstr_symbols"
HDL_POWER"PVCCIN_CPU0";
"G\NAC"2;
%"VCC_CORE"
"1","(-6675,4650)","0","mstr_symbols","I41";
;
HDL_POWER"VR_FET_SW_P12V_STBY_PVCCIN_CPU0"
CDS_LIB"mstr_symbols";
"A"3;
%"CAP"
"1","(-7200,4175)","0","mstr_discrete","I42";
;
CDS_SEC"1"
CDS_LOCATION"C6N11"
PACK_TYPE"0805"
PART_NUMBER"C95333-007"
MATERIAL"X6S"
TOLERANCE"10%"
VOLTAGE"16V"
VALUE"10UF"
LOCATION"C6N11"
CDS_LIB"mstr_discrete"
ROOM"PVCCIN_CPU0_PWR_VR"
SEC"1"
SEC_TYPE"0805";
"A"
$PN"1"3;
"B"
$PN"2"4;
%"GND"
"1","(-7025,3725)","0","mstr_symbols","I43";
;
ROOM"PVCCIN_CPU0_PWR_VR"
BOM_COST"PROC_VRD_VCCIN_CPU0"
BODY_TYPE"PLUMBING"
SIZE"1B"
CDS_LIB"mstr_symbols"
VOLTAGE"0"
HDL_POWER"GND";
"A\NAC"4;
%"VCC_CORE"
"1","(-575,2450)","0","mstr_symbols","I44";
;
HDL_POWER"VR_FET_SW_P12V_STBY_PVCCIN_CPU0"
CDS_LIB"mstr_symbols";
"A"5;
%"CAPP"
"1","(-925,1975)","0","mstr_discrete","I48";
;
CDS_SEC"1"
VALUE"270UF"
PACK_TYPE"2626"
PART_NUMBER"A31228-047"
LOCATION"C4D2"
VOLTAGE"16V"
TOLERANCE"20%"
MATERIAL"OSCON"
SEC_TYPE"2626"
SEC"1"
CDS_LOCATION"C4D2"
ROOM"PVCCIN_CPU0_FILTER_VR"
CDS_LIB"mstr_discrete";
"B"
$PN"2"6;
"A"
$PN"1"5;
%"GND"
"1","(-1175,1575)","0","mstr_symbols","I49";
;
HDL_POWER"GND"
CDS_LIB"mstr_symbols"
VOLTAGE"0"
SIZE"1B"
BODY_TYPE"PLUMBING"
BOM_COST"PROC_VRD_VCCIN_CPU0"
ROOM"PVCCIN_CPU0_FILTER_VR";
"A\NAC"6;
%"CAPP"
"1","(-1400,2000)","0","mstr_discrete","I50";
;
CDS_SEC"1"
LOCATION"C4E16"
VALUE"270UF"
TOLERANCE"20%"
VOLTAGE"16V"
PART_NUMBER"A31228-047"
PACK_TYPE"2626"
MATERIAL"OSCON"
ROOM"PVCCIN_CPU0_FILTER_VR"
CDS_LOCATION"C4E16"
SEC"1"
SEC_TYPE"2626"
CDS_LIB"mstr_discrete";
"B"
$PN"2"6;
"A"
$PN"1"5;
%"PVCCIN_CPU0"
"1","(-4625,2375)","0","mstr_symbols","I58";
;
BODY_TYPE"PLUMBING"
CDS_LIB"mstr_symbols"
VOLTAGE"2.0V"
HDL_POWER"PVCCIN_CPU0";
"G\NAC"7;
%"GND"
"1","(-4800,700)","0","mstr_symbols","I59";
;
HDL_POWER"GND"
VOLTAGE"0"
SIZE"1B"
CDS_LIB"mstr_symbols"
BODY_TYPE"PLUMBING"
BOM_COST"PROC_VRD_VCCIN_CPU0"
ROOM"PVCCIN_CPU0_VSENSE_VR";
"A\NAC"8;
%"RES"
"1","(-5475,2225)","0","mstr_discrete","I60";
;
MATERIAL"CHIP"
WATTAGE"1/16W"
TOLERANCE"1%"
LOCATION"R4E14"
PART_NUMBER"G21796-017"
PACK_TYPE"0402"
VALUE"100.0"
CDS_SEC"1"
$SEC"1"
ROOM"PVCCIN_CPU0_VSENSE_VR"
BOM_COST"PROC_VRD_VCCIN_CPU0"
CDS_LIB"mstr_discrete"
CDS_LOCATION"R4E14";
"B"
$PN"2"7;
"A"
$PN"1"16;
%"RES"
"1","(-5475,1825)","0","mstr_discrete","I61";
;
VALUE"0.0"
TOLERANCE"5%"
PART_NUMBER"G21497-005"
NO_XNET_CONNECTION"1"
LOCATION"R4E16"
WATTAGE"1/16W"
PACK_TYPE"0402"
MATERIAL"CHIP"
CDS_SEC"1"
$SEC"1"
CDS_LIB"mstr_discrete"
BOM_COST"PROC_VRD_VCCIN_CPU0"
CDS_LOCATION"R4E16"
ROOM"PVCCIN_CPU0_VSENSE_VR";
"B"
$PN"2"31;
"A"
$PN"1"16;
%"RES"
"1","(-5450,1375)","0","mstr_discrete","I62";
;
TOLERANCE"5%"
LOCATION"R4E17"
PART_NUMBER"G21497-005"
WATTAGE"1/16W"
VALUE"0.0"
PACK_TYPE"0402"
MATERIAL"CHIP"
NO_XNET_CONNECTION"1"
CDS_SEC"1"
$SEC"1"
BOM_COST"PROC_VRD_VCCIN_CPU0"
ROOM"PVCCIN_CPU0_VSENSE_VR"
CDS_LOCATION"R4E17"
CDS_LIB"mstr_discrete";
"B"
$PN"2"32;
"A"
$PN"1"30;
%"RES"
"2","(-6275,1625)","0","mstr_discrete","I63";
;
WATTAGE"1/16W"
MATERIAL"EMPTY"
TOLERANCE"1%"
VALUE"1.00K"
LOCATION"R4E15"
NO_XNET_CONNECTION"1"
PACK_TYPE"0402"
PART_NUMBER"G21796-026"
BOM_COST"PROC_VRD_VCCIN_CPU0"
CDS_SEC"1"
$SEC"1"
ROOM"PVCCIN_CPU0_VSENSE_VR"
CDS_LOCATION"R4E15"
CDS_LIB"mstr_discrete";
"A"
$PN"1"16;
"B"
$PN"2"30;
%"RES"
"1","(-5450,975)","0","mstr_discrete","I64";
;
MATERIAL"CHIP"
PACK_TYPE"0402"
TOLERANCE"1%"
PART_NUMBER"G21796-017"
WATTAGE"1/16W"
VALUE"100.0"
LOCATION"R4E18"
CDS_SEC"1"
$SEC"1"
CDS_LOCATION"R4E18"
ROOM"PVCCIN_CPU0_VSENSE_VR"
BOM_COST"PROC_VRD_VCCIN_CPU0"
CDS_LIB"mstr_discrete";
"B"
$PN"2"8;
"A"
$PN"1"30;
%"CAPP"
"1","(-575,1975)","0","mstr_discrete","I67";
;
CDS_SEC"1"
LOCATION"C4C12"
TOLERANCE"20%"
VOLTAGE"16V"
MATERIAL"OSCON"
VALUE"270UF"
PART_NUMBER"A31228-047"
PACK_TYPE"2626"
SEC_TYPE"2626"
SEC"1"
ROOM"PVCCIN_CPU0_FILTER_VR"
CDS_LOCATION"C4C12"
CDS_LIB"mstr_discrete";
"B"
$PN"2"6;
"A"
$PN"1"5;
%"P12V_STBY"
"1","(-3325,2425)","0","mstr_symbols","I68";
;
CDS_LIB"mstr_symbols"
SIZE"1B"
BODY_TYPE"PLUMBING"
VOLTAGE"12.0V"
HDL_POWER"P12V_STBY";
"G\NAC"9;
%"P5V_STBY"
"1","(-4675,4875)","0","mstr_symbols","I69";
;
CDS_LIB"mstr_symbols"
SIZE"1B"
BODY_TYPE"PLUMBING"
VOLTAGE"5.0V"
HDL_POWER"P5V_STBY";
"G\NAC"10;
%"CAP_A"
"1","(-400,3425)","0","dev_discrete","I70";
;
GROUP"PWR_MLCC_CAP"
LOCATION"C6R2"
PART_NUMBER"E15431-004"
PACK_TYPE"0603V"
MATERIAL"X6S"
TOLERANCE"20%"
VOLTAGE"4V"
VALUE"22.0UF"
SEC"1"
SEC_TYPE"0603V"
CDS_SEC"1"
CDS_LOCATION"C6R2"
CDS_LIB"dev_discrete";
"B"
$PN"2"11;
"A"
$PN"1"2;
%"IR354XX"
"1","(-3125,3925)","0","mstr_discrete","I71";
;
LOCATION"EU4C2"
PART_NUMBER"H73688-001"
MATERIAL"IC"
VALUE"IR35411"
CDS_LIB"mstr_discrete"
PACK_TYPE"SM"
CDS_SEC"1"
$SEC"1"
CDS_LOCATION"EU4C2";
"TOUT_FLT"
$PN"36"27;
"NC"
$PN"31"0;
"OCSET"
$PN"37"29;
"IOUT"
$PN"38"28;
"SW"
$PN"10"22;
"BOOST"
$PN"33"23;
"REFIN"
$PN"39"18;
"PWM"
$PN"34"21;
"PHASE"
$PN"32"17;
"VIN<0>"
$PN"25"3;
"VCC"
$PN"3"19;
"VIN<1>"
$PN"30"3;
"EN"
$PN"35"10;
"VDRV"
$PN"4"10;
"VOS"
$PN"1"2;
"LGND"
$PN"2"1;
"PGND<1>"
$PN"7"1;
"PGND<2>"
$PN"40"1;
"PGND<0>"
$PN"5"1;
"GL<0>"
$PN"6"20;
"GL<1>"
$PN"41"26;
%"GND"
"1","(-400,2900)","0","mstr_symbols","I8";
;
HDL_POWER"GND"
CDS_LIB"mstr_symbols"
SIZE"1B"
VOLTAGE"0"
BODY_TYPE"PLUMBING"
BOM_COST"PROC_VRD_VCCIN_CPU0"
ROOM"PVCCIN_CPU0_PWR_VR";
"A\NAC"11;
%"RES"
"2","(-400,4075)","0","mstr_discrete","I83";
;
CDS_SEC"1"
CDS_LOCATION"R4D68"
TOLERANCE"1%"
VALUE"68.1K"
LOCATION"R4D68"
PACK_TYPE"0402"
WATTAGE"1/16W"
MATERIAL"EMPTY"
PART_NUMBER"G21796-187"
CDS_LIB"mstr_discrete"
SEC"1"
SEC_TYPE"0402";
"A"
$PN"1"29;
"B"
$PN"2"12;
%"GND"
"1","(-400,3850)","0","mstr_symbols","I84";
;
ROOM"PVCCIN_CPU0_PWR_VR"
BOM_COST"PROC_VRD_VCCIN_CPU0"
BODY_TYPE"PLUMBING"
SIZE"1B"
CDS_LIB"mstr_symbols"
VOLTAGE"0"
HDL_POWER"GND";
"A\NAC"12;
%"CAP_A"
"1","(-3850,3425)","0","dev_discrete","I85";
;
CDS_SEC"1"
CDS_LOCATION"CT36"
VOLTAGE"16V"
PART_NUMBER"A36096-030"
POP"NOPOP"
TOLERANCE"10%"
MATERIAL"X7R"
PACK_TYPE"0402V"
VALUE"0.1UF"
LOCATION"CT36"
SEC_TYPE"0402V"
SEC"1"
ROOM"PVCCIN_CPU0_PWR_VR"
CDS_LIB"dev_discrete";
"B"
$PN"2"13;
"A"
$PN"1"18;
%"GND"
"1","(-3850,3175)","0","mstr_symbols","I86";
;
BODY_TYPE"PLUMBING"
ROOM"PVCCIN_CPU0_PWR_VR"
BOM_COST"PROC_VRD_VCCIN_CPU0"
SIZE"1B"
VOLTAGE"0"
HDL_POWER"GND"
CDS_LIB"mstr_symbols";
"A\NAC"13;
%"CAP"
"1","(-2075,3950)","0","mstr_discrete","I88";
;
CDS_SEC"1"
CDS_LOCATION"CT34"
PACK_TYPE"0402LF"
POP"NOPOP"
LOCATION"CT34"
VALUE"1000PF"
VOLTAGE"50V"
TOLERANCE"10%"
MATERIAL"X7R"
PART_NUMBER"A36096-046"
SEC_TYPE"0402LF"
SEC"1"
ROOM"VDDQ_KLM_PWR_VR"
CDS_LIB"mstr_discrete";
"A"
$PN"1"27;
"B"
$PN"2"14;
%"GND"
"1","(-2075,3750)","0","mstr_symbols","I89";
;
HDL_POWER"GND"
SIZE"1B"
BODY_TYPE"PLUMBING"
VOLTAGE"0"
ROOM"VDDQ_KLM_PWR_VR"
CDS_LIB"mstr_symbols";
"A\NAC"14;
%"CAP_A"
"1","(-700,3425)","0","dev_discrete","I9";
;
GROUP"PWR_MLCC_CAP"
MATERIAL"X6S"
LOCATION"C4D12"
VALUE"22.0UF"
VOLTAGE"4V"
TOLERANCE"20%"
PACK_TYPE"0603V"
PART_NUMBER"E15431-004"
CDS_LOCATION"C4D12"
BOM_COST"PROC_VRD_VCCIN_CPU0"
CDS_LIB"dev_discrete"
CDS_SEC"1"
ROOM"PVCCIN_CPU0_PWR_VR"
SEC_TYPE"0603V"
SEC"1";
"B"
$PN"2"11;
"A"
$PN"1"2;
%"GND"
"1","(-1975,2975)","0","mstr_symbols","I92";
;
ROOM"PVCCIN_CPU0_PWR_VR"
BOM_COST"PROC_VRD_VCCIN_CPU0"
BODY_TYPE"PLUMBING"
VOLTAGE"0"
SIZE"1B"
HDL_POWER"GND"
CDS_LIB"mstr_symbols";
"A\NAC"15;
%"CAP"
"1","(-1975,3475)","0","mstr_discrete","I97";
;
CDS_SEC"1"
CDS_LOCATION"CT35"
MATERIAL"X7R"
VALUE"1000PF"
TOLERANCE"10%"
LOCATION"CT35"
PART_NUMBER"A36096-046"
PACK_TYPE"0402LF"
POP"NOPOP"
VOLTAGE"50V"
SEC_TYPE"0402LF"
SEC"1"
ROOM"VDDQ_KLM_PWR_VR"
CDS_LIB"mstr_discrete";
"A"
$PN"1"22;
"B"
$PN"2"24;
%"RES"
"1","(-4875,3725)","0","mstr_discrete","I99";
;
CDS_SEC"1"
CDS_LOCATION"RT23"
TOLERANCE"5.0%"
MATERIAL"CHIP"
PART_NUMBER"G22178-002"
VALUE"0"
LOCATION"RT23"
WATTAGE"1/10W"
PACK_TYPE"0603"
SEC_TYPE"0603"
SEC"1"
ROOM"NIC_SPRV"
BOM_COST"NT_GBE_BASE"
CDS_LIB"mstr_discrete";
"B"
$PN"2"23;
"A"
$PN"1"25;
END.
